FILE_TYPE = CONNECTIVITY;
{Allegro Design Entry HDL 16.6-p007 (v16-6-112F) 10/10/2012}
"PAGE_NUMBER" = 111;
0"NC";
1"GND\g";
2"GND\g";
3"PVCCIO_CPU0\g";
4"GND\g";
5"P3V3_STBY\g";
6"P3V3_STBY\g";
7"P1V05_PCH_STBY\g";
8"GND\g";
9"P1V05_PCH_STBY\g";
10"P1V05_PCH_STBY\g";
11"GND\g";
12"P3V3_STBY\g";
13"GND\g";
14"GND\g";
15"P3V3\g";
16"SPI_PCH_MOSI";
17"TP_XDP_CPU_OBSDATA_C2";
18"TP_XDP_CPU_OBSDATA_C3";
19"TP_XDP_CPU_OBSDATA_C0";
20"TP_XDP_CPU_OBSDATA_C1";
21"XDP_SPI_PCH_MOSI_BOOT_HALT_N";
22"TP_XDP_CPU_OBSFN_C0";
23"XDP_OBSFN_B1_MBP7_N";
24"XDP_OBSFN_B0_MBP6_N";
25"FM_DEBUG_RST_BTN_N";
26"XDP_SYSPWROK";
27"FM_DEBUG_RST_BTN_R1_N";
28"XDP_PWRGD_RST_N";
29"XDP_RST_CO_N";
30"XDP_RST_CO_N";
31"TP_XDP_CPU_OBSDATA_D3";
32"TP_XDP_CPU_OBSDATA_D1";
33"TP_XDP_CPU_OBSDATA_D2";
34"TP_XDP_CPU_OBSDATA_D0";
35"XDP_PRESENT_N";
36"XDP_TMS";
37"XDP_TRST_N";
38"XDP_TDI";
39"XDP_TDO";
40"XDP_ITP_PMODE";
41"CLK_100M_PCH_XDP_DN";
42"CLK_100M_PCH_XDP_DP";
43"XDP_CPU_TCK0";
44"XDP_DEBUG_CONSENT_N";
45"XDP_RSMRST_N";
46"TP_XDP_OBSDATA_B2";
47"TP_XDP_OBSDATA_B3";
48"TP_XDP_OBSDATA_B1";
49"TP_XDP_OBSDATA_B0";
50"TP_XDP_OBSFN_B1";
51"TP_XDP_OBSFN_B0";
52"TP_XDP_OBSDATA_A3";
53"TP_XDP_OBSDATA_A2";
54"TP_XDP_OBSDATA_A1";
55"TP_XDP_OBSDATA_A0";
56"SMB_HOST_STBY_LVC3_SCL";
57"XDP_PCH_TCK1";
58"SMB_HOST_STBY_LVC3_SDA";
59"XDP_SYSPWROK";
60"XDP_CPU_PWR_DEBUG_N";
61"XDP_PWRGD_RST_N";
62"XDP_PRDY_N";
63"XDP_PREQ_N";
64"SPI_PCH_IO2";
65"XDP_CPU_PWR_DEBUG_N";
66"XDP_CPU_TCK_BUF";
67"XDP_PCH_CPU_TCK0";
68"XDP_PRESENT_N";
69"XDP_ITP_PMODE";
70"RST_RSMRST_N";
71"XDP_CPU_GTL_TCK_R2";
%"CAP_A"
"1","(2750,1900)","1","dev_discrete","I10";
;
SEC"1"
BOM_COST"DEBUG"
ROOM"DEBUG"
CDS_SEC"1"
CDS_LOCATION"C9A2"
CDS_LIB"dev_discrete"
SEC_TYPE"0402V"
PACK_TYPE"0402V"
MATERIAL"X7R"
TOLERANCE"10%"
PART_NUMBER"A36096-030"
VOLTAGE"16V"
LOCATION"C9A2"
VALUE"0.1UF";
"B"
$PN"2"8;
"A"
$PN"1"26;
%"RES"
"1","(2725,1700)","0","mstr_discrete","I11";
;
CDS_SEC"1"
ROOM"DEBUG"
SEC_TYPE"0402"
BOM_COST"DEBUG"
SEC"1"
CDS_LIB"mstr_discrete"
CDS_LOCATION"R9A14"
MATERIAL"CHIP"
PART_NUMBER"G21796-026"
PACK_TYPE"0402"
TOLERANCE"1%"
LOCATION"R9A14"
WATTAGE"1/16W"
VALUE"1.00K";
"B"
$PN"2"5;
"A"
$PN"1"29;
%"CAP_A"
"1","(2800,1450)","1","dev_discrete","I12";
;
ROOM"DEBUG"
BOM_COST"DEBUG"
CDS_SEC"1"
SEC_TYPE"0402V"
SEC"1"
CDS_LOCATION"C9A5"
CDS_LIB"dev_discrete"
MATERIAL"X7R"
LOCATION"C9A5"
PACK_TYPE"0402V"
PART_NUMBER"A36096-030"
TOLERANCE"10%"
VOLTAGE"16V"
VALUE"0.1UF";
"B"
$PN"2"11;
"A"
$PN"1"29;
%"RES"
"1","(2725,1125)","0","mstr_discrete","I13";
;
CDS_SEC"1"
SEC"1"
SEC_TYPE"0402"
BOM_COST"DEBUG"
ROOM"DEBUG"
CDS_LOCATION"R1L23"
CDS_LIB"mstr_discrete"
MATERIAL"CHIP"
PART_NUMBER"G21796-026"
PACK_TYPE"0402"
TOLERANCE"1%"
LOCATION"R1L23"
WATTAGE"1/16W"
VALUE"1.00K";
"B"
$PN"2"5;
"A"
$PN"1"28;
%"CAP_A"
"1","(2825,925)","1","dev_discrete","I14";
;
SEC"1"
BOM_COST"DEBUG"
ROOM"DEBUG"
SEC_TYPE"0402V"
CDS_SEC"1"
CDS_LOCATION"C1L8"
CDS_LIB"dev_discrete"
PACK_TYPE"0402V"
LOCATION"C1L8"
MATERIAL"X7R"
PART_NUMBER"A36096-030"
VOLTAGE"16V"
TOLERANCE"10%"
VALUE"0.1UF";
"B"
$PN"2"14;
"A"
$PN"1"28;
%"GND"
"1","(875,2625)","0","mstr_symbols","I24";
;
HDL_POWER"GND"
SIZE"1B"
CDS_LIB"mstr_symbols"
VOLTAGE"0.0V"
BODY_TYPE"PLUMBING"
BOM_COST"DEBUG"
ROOM"CPU_XDP_DEBUG";
"A\NAC"1;
%"CAP_A"
"1","(750,2925)","2","dev_discrete","I25";
;
CDS_SEC"1"
$SEC"1"
ROOM"DEBUG"
CDS_LOCATION"C9A6"
BOM_COST"DEBUG"
CDS_LIB"dev_discrete"
LOCATION"C9A6"
VALUE"1.0UF"
TOLERANCE"10%"
VOLTAGE"6.3V"
MATERIAL"X6S"
PACK_TYPE"0402V"
PART_NUMBER"D97712-004";
"B"
$PN"2"1;
"A"
$PN"1"9;
%"SCONN60_C21100002"
"1","(350,3950)","0","mstr_sconn","I26";
;
CDS_SEC"1"
SEC"1"
SEC_TYPE"SMLF"
BOM_COST"DEBUG"
ROOM"DEBUG"
CDS_LOCATION"J9A3"
ALLOW_CONNECT"TRUE"
CDS_LIB"mstr_sconn"
MATERIAL"CONN"
PACK_TYPE"SMLF"
LOCATION"J9A3"
PART_NUMBER"C21100-002";
"IO11 \B"
$PN"11"54;
"IO9 \B"
$PN"9"55;
"IO3 \B"
$PN"3"63;
"IO1 \B"
$PN"1"44;
"IO59 \B"
$PN"59"2;
"IO55 \B"
$PN"55"57;
"IO57 \B"
$PN"57"43;
"IO51 \B"
$PN"51"58;
"IO53 \B"
$PN"53"56;
"IO49 \B"
$PN"49"2;
"IO45 \B"
$PN"45"60;
"IO47 \B"
$PN"47"59;
"IO39 \B"
$PN"39"45;
"IO41 \B"
$PN"41"61;
"IO43 \B"
$PN"43"10;
"IO37 \B"
$PN"37"2;
"IO35 \B"
$PN"35"47;
"IO29 \B"
$PN"29"48;
"IO31 \B"
$PN"31"2;
"IO33 \B"
$PN"33"46;
"IO25 \B"
$PN"25"2;
"IO27 \B"
$PN"27"49;
"IO23 \B"
$PN"23"50;
"IO19 \B"
$PN"19"2;
"IO21 \B"
$PN"21"51;
"IO15 \B"
$PN"15"53;
"IO17 \B"
$PN"17"52;
"IO13 \B"
$PN"13"2;
"IO5 \B"
$PN"5"62;
"IO7 \B"
$PN"7"2;
"IO60 \B"
$PN"60"35;
"IO56 \B"
$PN"56"38;
"IO58 \B"
$PN"58"36;
"IO52 \B"
$PN"52"39;
"IO54 \B"
$PN"54"37;
"IO50 \B"
$PN"50"1;
"IO46 \B"
$PN"46"40;
"IO48 \B"
$PN"48"30;
"IO40 \B"
$PN"40"42;
"IO42 \B"
$PN"42"41;
"IO44 \B"
$PN"44"9;
"IO38 \B"
$PN"38"1;
"IO36 \B"
$PN"36"31;
"IO30 \B"
$PN"30"32;
"IO32 \B"
$PN"32"1;
"IO34 \B"
$PN"34"33;
"IO26 \B"
$PN"26"1;
"IO28 \B"
$PN"28"34;
"IO24 \B"
$PN"24"23;
"IO20 \B"
$PN"20"1;
"IO22 \B"
$PN"22"24;
"IO16 \B"
$PN"16"17;
"IO18 \B"
$PN"18"18;
"IO14 \B"
$PN"14"1;
"IO10 \B"
$PN"10"19;
"IO12 \B"
$PN"12"20;
"IO2 \B"
$PN"2"1;
"IO6 \B"
$PN"6"21;
"IO8 \B"
$PN"8"1;
"IO4 \B"
$PN"4"22;
%"CAP_A"
"1","(0,2925)","0","dev_discrete","I30";
;
$SEC"1"
CDS_SEC"1"
ROOM"DEBUG"
BOM_COST"DEBUG"
CDS_LOCATION"C1L5"
CDS_LIB"dev_discrete"
MATERIAL"X6S"
VOLTAGE"6.3V"
PACK_TYPE"0402V"
TOLERANCE"10%"
VALUE"1.0UF"
PART_NUMBER"D97712-004"
LOCATION"C1L5";
"B"
$PN"2"2;
"A"
$PN"1"10;
%"RES"
"1","(-2250,4650)","0","mstr_discrete","I37";
;
CDS_SEC"1"
ROOM"DEBUG"
SEC"1"
CDS_LIB"mstr_discrete"
SEC_TYPE"0402"
BOM_COST"DEBUG"
CDS_LOCATION"R2P2"
MATERIAL"CHIP"
LOCATION"R2P2"
PACK_TYPE"0402"
PART_NUMBER"G21796-026"
WATTAGE"1/16W"
TOLERANCE"1%"
VALUE"1.00K";
"B"
$PN"2"44;
"A"
$PN"1"64;
%"GND"
"1","(-100,2625)","0","mstr_symbols","I39";
;
HDL_POWER"GND"
CDS_LIB"mstr_symbols"
SIZE"1B"
VOLTAGE"0.0V"
BOM_COST"DEBUG"
BODY_TYPE"PLUMBING"
ROOM"CPU_XDP_DEBUG";
"A\NAC"2;
%"PVCCIO_CPU0"
"1","(-925,1600)","0","mstr_symbols","I54";
;
BODY_TYPE"PLUMBING"
CDS_LIB"mstr_symbols"
HDL_POWER"PVCCIO_CPU0"
VOLTAGE"1.1V";
"G\NAC"3;
%"RES"
"1","(-1475,1425)","0","mstr_discrete","I55";
;
CDS_SEC"1"
SEC"1"
ROOM"DEBUG"
SEC_TYPE"0402"
BOM_COST"DEBUG"
CDS_LIB"mstr_discrete"
CDS_LOCATION"R9A4"
PACK_TYPE"0402"
PART_NUMBER"G21796-077"
MATERIAL"CHIP"
LOCATION"R9A4"
TOLERANCE"1%"
WATTAGE"1/16W"
VALUE"475.0";
"B"
$PN"2"3;
"A"
$PN"1"68;
%"RES"
"1","(-1475,1100)","0","mstr_discrete","I56";
;
CDS_SEC"1"
SEC"1"
ROOM"DEBUG"
CDS_LIB"mstr_discrete"
BOM_COST"DEBUG"
SEC_TYPE"0402"
CDS_LOCATION"R1L17"
PACK_TYPE"0402"
PART_NUMBER"G21796-009"
LOCATION"R1L17"
TOLERANCE"1%"
VALUE"150.0"
WATTAGE"1/16W"
MATERIAL"CHIP";
"B"
$PN"2"3;
"A"
$PN"1"65;
%"RES"
"1","(-1375,500)","0","mstr_discrete","I57";
;
CDS_SEC"1"
SEC"1"
CDS_LOCATION"R9A17"
SEC_TYPE"0402"
BOM_COST"DEBUG"
ROOM"DEBUG"
CDS_LIB"mstr_discrete"
PART_NUMBER"G21796-026"
LOCATION"R9A17"
MATERIAL"CHIP"
PACK_TYPE"0402"
TOLERANCE"1%"
WATTAGE"1/16W"
VALUE"1.00K";
"B"
$PN"2"7;
"A"
$PN"1"69;
%"GND"
"1","(-1175,800)","0","mstr_symbols","I58";
;
HDL_POWER"GND"
CDS_LIB"mstr_symbols"
VOLTAGE"0.0V"
SIZE"1B"
BODY_TYPE"PLUMBING"
BOM_COST"DEBUG"
ROOM"CPU_XDP_DEBUG";
"A\NAC"4;
%"CAP_A"
"1","(-1475,875)","1","dev_discrete","I59";
;
SEC"1"
BOM_COST"DEBUG"
ROOM"DEBUG"
CDS_SEC"1"
CDS_LIB"dev_discrete"
CDS_LOCATION"C9A4"
SEC_TYPE"0402V"
PACK_TYPE"0402V"
MATERIAL"X7R"
LOCATION"C9A4"
PART_NUMBER"A36096-030"
VOLTAGE"16V"
TOLERANCE"10%"
VALUE"0.1UF";
"B"
$PN"2"4;
"A"
$PN"1"65;
%"RES"
"1","(2725,2150)","0","mstr_discrete","I6";
;
CDS_SEC"1"
SEC"1"
ROOM"DEBUG"
SEC_TYPE"0402"
BOM_COST"DEBUG"
CDS_LOCATION"R1L13"
CDS_LIB"mstr_discrete"
MATERIAL"CHIP"
PART_NUMBER"G21796-026"
PACK_TYPE"0402"
LOCATION"R1L13"
TOLERANCE"1%"
WATTAGE"1/16W"
VALUE"1.00K";
"B"
$PN"2"5;
"A"
$PN"1"26;
%"RES"
"1","(-2175,3700)","0","mstr_discrete","I60";
;
CDS_SEC"1"
ROOM"DEBUG"
SEC"1"
BOM_COST"DEBUG"
SEC_TYPE"0402"
CDS_LIB"mstr_discrete"
CDS_LOCATION"R9A15"
MATERIAL"CHIP"
PACK_TYPE"0402"
WATTAGE"1/16W"
LOCATION"R9A15"
PART_NUMBER"G21796-026"
TOLERANCE"1%"
VALUE"1.00K";
"B"
$PN"2"45;
"A"
$PN"1"70;
%"P3V3_STBY"
"1","(3250,2300)","0","mstr_symbols","I65";
;
SIZE"1B"
CDS_LIB"mstr_symbols"
VOLTAGE"3.3V"
BODY_TYPE"PLUMBING"
HDL_POWER"P3V3_STBY";
"G\NAC"5;
%"RES"
"2","(2175,2800)","0","mstr_discrete","I66";
;
CDS_SEC"1"
BOM_COST"M-SATA"
CDS_LOCATION"R1L28"
SEC_TYPE"0402"
ROOM"M-SATA"
SEC"1"
CDS_LIB"mstr_discrete"
WATTAGE"1/16W"
MATERIAL"CHIP"
PACK_TYPE"0402"
VALUE"4.75K"
PART_NUMBER"G21796-072"
LOCATION"R1L28"
TOLERANCE"1%";
"A"
$PN"1"6;
"B"
$PN"2"27;
%"P3V3_STBY"
"1","(2175,2975)","0","mstr_symbols","I67";
;
SIZE"1B"
VOLTAGE"3.3V"
BODY_TYPE"PLUMBING"
CDS_LIB"mstr_symbols"
HDL_POWER"P3V3_STBY";
"G\NAC"6;
%"RES"
"1","(2950,2600)","0","mstr_discrete","I68";
;
CDS_SEC"1"
ROOM"M-SATA"
SEC_TYPE"0402"
SEC"1"
CDS_LIB"mstr_discrete"
CDS_LOCATION"R1L29"
PACK_TYPE"0402"
PART_NUMBER"G21796-074"
LOCATION"R1L29"
TOLERANCE"1%"
MATERIAL"CHIP"
VALUE"33.2"
WATTAGE"1/16W";
"B"
$PN"2"25;
"A"
$PN"1"27;
%"P1V05_PCH_STBY"
"1","(-850,650)","0","mstr_symbols","I69";
;
VOLTAGE"1.05V"
HDL_POWER"P1V05_PCH_STBY"
CDS_LIB"mstr_symbols"
BODY_TYPE"PLUMBING";
"G\NAC"7;
%"GND"
"1","(3075,1825)","0","mstr_symbols","I7";
;
CDS_LIB"mstr_symbols"
HDL_POWER"GND"
SIZE"1B"
BOM_COST"DEBUG"
BODY_TYPE"PLUMBING"
VOLTAGE"0.0V"
ROOM"CPU_XDP_DEBUG";
"A\NAC"8;
%"P1V05_PCH_STBY"
"1","(750,4750)","0","mstr_symbols","I70";
;
VOLTAGE"1.05V"
HDL_POWER"P1V05_PCH_STBY"
CDS_LIB"mstr_symbols"
BODY_TYPE"PLUMBING";
"G\NAC"9;
%"P1V05_PCH_STBY"
"1","(0,4750)","0","mstr_symbols","I71";
;
CDS_LIB"mstr_symbols"
HDL_POWER"P1V05_PCH_STBY"
VOLTAGE"1.05V"
BODY_TYPE"PLUMBING";
"G\NAC"10;
%"RES"
"1","(-1900,3075)","0","mstr_discrete","I74";
;
CDS_SEC"1"
CDS_LIB"mstr_discrete"
CDS_LOCATION"R9A3"
SEC"1"
SEC_TYPE"0402"
ROOM"DEBUG"
MATERIAL"CHIP"
PACK_TYPE"0402"
TOLERANCE"5%"
LOCATION"R9A3"
PART_NUMBER"G21497-005"
VALUE"0.0"
WATTAGE"1/16W";
"B"
$PN"2"43;
"A"
$PN"1"67;
%"GND"
"1","(3100,1375)","0","mstr_symbols","I8";
;
HDL_POWER"GND"
SIZE"1B"
CDS_LIB"mstr_symbols"
BODY_TYPE"PLUMBING"
BOM_COST"DEBUG"
VOLTAGE"0.0V"
ROOM"CPU_XDP_DEBUG";
"A\NAC"11;
%"RES"
"2","(-2925,2675)","0","mstr_discrete","I83";
;
CDS_SEC"1"
SEC"1"
SEC_TYPE"0402"
ROOM"DEBUG"
CDS_LOCATION"R9A2"
CDS_LIB"mstr_discrete"
PART_NUMBER"G21796-074"
WATTAGE"1/16W"
TOLERANCE"1%"
VALUE"33.2"
LOCATION"R9A2"
MATERIAL"EMPTY"
PACK_TYPE"0402";
"A"
$PN"1"67;
"B"
$PN"2"71;
%"TTL1G07_A"
"1","(1775,2600)","0","mstr_ttl","I85";
;
CDS_SEC"1"
PACK_TYPE"SOP"
CDS_LIB"mstr_ttl"
CDS_LOCATION"U1L4"
SEC"1"
SEC_TYPE"SOP"
BOM_COST"M-SATA"
ROOM"M-SATA"
LOCATION"U1L4"
VALUE"74LVC1G07"
MATERIAL"IC"
PART_NUMBER"C88419-001"
POWER_GROUP"VCC=P3V3_STBY;GND=GND";
"Y"
$PN"4"27;
"A"
$PN"2"30;
%"P3V3_STBY"
"1","(3900,3925)","0","mstr_symbols","I86";
;
BODY_TYPE"PLUMBING"
SIZE"1B"
CDS_LIB"mstr_symbols"
VOLTAGE"3.3V"
HDL_POWER"P3V3_STBY";
"G\NAC"12;
%"CAP_A"
"1","(3900,3625)","0","dev_discrete","I87";
;
BOM_COST"DEBUG"
SEC_TYPE"0402V"
SEC"1"
CDS_LOCATION"C1L11"
CDS_SEC"1"
CDS_LIB"dev_discrete"
ROOM"DEBUG"
PART_NUMBER"A36096-030"
VOLTAGE"16V"
VALUE"0.1UF"
LOCATION"C1L11"
TOLERANCE"10%"
MATERIAL"X7R"
PACK_TYPE"0402V";
"B"
$PN"2"13;
"A"
$PN"1"12;
%"GND"
"1","(3900,3325)","0","mstr_symbols","I88";
;
HDL_POWER"GND"
CDS_LIB"mstr_symbols"
BODY_TYPE"PLUMBING"
SIZE"1B"
VOLTAGE"0.0V";
"A\NAC"13;
%"RES"
"1","(2050,4550)","0","mstr_discrete","I89";
;
CDS_SEC"1"
CDS_LIB"mstr_discrete"
SEC"1"
SEC_TYPE"0402"
BOM_COST"DEBUG"
ROOM"DEBUG"
CDS_LOCATION"R8E2"
PACK_TYPE"0402"
MATERIAL"CHIP"
TOLERANCE"1%"
PART_NUMBER"G21796-026"
LOCATION"R8E2"
WATTAGE"1/16W"
VALUE"1.00K";
"B"
$PN"2"16;
"A"
$PN"1"21;
%"GND"
"1","(3125,850)","0","mstr_symbols","I9";
;
HDL_POWER"GND"
SIZE"1B"
VOLTAGE"0.0V"
CDS_LIB"mstr_symbols"
BODY_TYPE"PLUMBING"
BOM_COST"DEBUG"
ROOM"CPU_XDP_DEBUG";
"A\NAC"14;
%"NPN_DUAL"
"2","(-2300,2325)","0","mstr_discrete","I93";
;
CDS_SEC"2"
ROOM"DEBUG"
SEC"2"
SEC_TYPE"SSOPLF"
PACK_TYPE"SSOPLF"
CDS_LIB"mstr_discrete"
CDS_LOCATION"Q9A1"
VALUE"MBT3904"
MATERIAL"EMPTY"
PART_NUMBER"C52264-001"
LOCATION"Q9A1";
"B <SIZE-1..0>"
$PN"2"66;
"E <SIZE-1..0>"
$PN"1"71;
"C <SIZE-1..0>"
$PN"6"66;
%"NPN_DUAL"
"1","(-1650,2275)","0","mstr_discrete","I94";
;
CDS_SEC"1"
ROOM"DEBUG"
SEC_TYPE"SSOPLF"
SEC"1"
PACK_TYPE"SSOPLF"
CDS_LOCATION"Q9A1"
CDS_LIB"mstr_discrete"
VALUE"MBT3904"
PART_NUMBER"C52264-001"
MATERIAL"EMPTY"
LOCATION"Q9A1";
"C <SIZE-1..0>"
$PN"3"15;
"B <SIZE-1..0>"
$PN"5"66;
"E <SIZE-1..0>"
$PN"4"43;
%"RES"
"2","(-2075,2675)","2","mstr_discrete","I95";
;
CDS_SEC"1"
CDS_LOCATION"R9A1"
SEC_TYPE"0402"
SEC"1"
ROOM"DEBUG"
CDS_LIB"mstr_discrete"
LOCATION"R9A1"
MATERIAL"EMPTY"
VALUE"1.00K"
TOLERANCE"1%"
WATTAGE"1/16W"
PART_NUMBER"G21796-026"
PACK_TYPE"0402";
"A"
$PN"1"15;
"B"
$PN"2"66;
%"P3V3"
"1","(-2075,2900)","0","mstr_symbols","I96";
;
SIZE"1B"
CDS_LIB"mstr_symbols"
VOLTAGE"3.3V"
BODY_TYPE"PLUMBING"
HDL_POWER"P3V3";
"G\NAC"15;
END.
